# T6G (Grand Teton) — schematic netlist excerpt (pin names and nets, part order shuffled) for the footprints in the layout excerpt that follows; sources: Cadence DE-HDL packaged netlist, KiCad conversion of 04192023_DAF0TMB3IC0_F0TG_MB_C_brd_V02_OCP.brd

C3927  Q_CAP  22UF 4V 20% X6S  pkg C0402  page 70 : A = PVDDCR_SOC_P0 ; B = GND

PQ12  MOSFET_PCH_GDS_ESD_PROTECTED  PJA3415AE IC  pkg SOT23_GDSXC  page 217
  D  = PVDDCR_CPU1_P1_EN1_ADDR_CFG
  G  = PVDDIO_P1_EN_G
  S  = P3V3_AUX

(kicad_pcb
	(version 20260206)
	(generator "pcbnew")
	(generator_version "10.0")
	(general
		(thickness 1.6)
		(legacy_teardrops no)
	)
	(paper "A4")
	(title_block
		(title "04192023_DAF0TMB3IC0_F0TG_MB_C_brd_V02_OCP.brd")
		(comment 1 "Grand Teton / footprints 726-727 of 8354")
	)
	(layers
		(0 "F.Cu" signal "TOP")
		(4 "In1.Cu" signal "GND")
		(6 "In2.Cu" signal "IN1")
		(8 "In3.Cu" signal "GND1")
		(10 "In4.Cu" signal "IN2")
		(12 "In5.Cu" signal "GND2")
		(14 "In6.Cu" signal "IN3")
		(16 "In7.Cu" signal "GND3")
		(18 "In8.Cu" signal "VCC")
		(20 "In9.Cu" signal "VCC1")
		(22 "In10.Cu" signal "GND4")
		(24 "In11.Cu" signal "IN4")
		(26 "In12.Cu" signal "GND5")
		(28 "In13.Cu" signal "IN5")
		(30 "In14.Cu" signal "GND6")
		(32 "In15.Cu" signal "IN6")
		(34 "In16.Cu" signal "GND7")
		(2 "B.Cu" signal "BOTTOM")
		(9 "F.Adhes" user "F.Adhesive")
		(11 "B.Adhes" user "B.Adhesive")
		(13 "F.Paste" user "Package Geometry/Pastemask Top")
		(15 "B.Paste" user "Package Geometry/Pastemask Bottom")
		(5 "F.SilkS" user "Ref Des/Silkscreen Top")
		(7 "B.SilkS" user "Ref Des/Silkscreen Bottom")
		(1 "F.Mask" user "Board Geometry/Soldermask Top")
		(3 "B.Mask" user "Board Geometry/Soldermask Bottom")
		(17 "Dwgs.User" user "User.Drawings")
		(19 "Cmts.User" user "User.Comments")
		(21 "Eco1.User" user "User.Eco1")
		(23 "Eco2.User" user "User.Eco2")
		(25 "Edge.Cuts" user "Board Geometry/Outline")
		(27 "Margin" user)
		(31 "F.CrtYd" user "Package Geometry/Place Bound Top")
		(29 "B.CrtYd" user "Package Geometry/Place Bound Bottom")
		(35 "F.Fab" user "Ref Des/Assembly Top")
		(33 "B.Fab" user "Ref Des/Assembly Bottom")
	)
	(footprint ""
		(layer "F.Cu")
		(at 19.558 -366.649 90)
		(property "Reference" "PQ12"
			(at -1.464818 -3.07594 90)
			(unlocked yes)
			(layer "F.SilkS")
			(effects
				(font
					(size 0.7874 0.5842)
					(thickness 0.1524)
				)
				(justify left)
			)
		)
		(property "Value" ""
			(at 0 0 90)
			(layer "F.Fab")
			(effects
				(font
					(size 1.27 1.27)
				)
			)
		)
		(duplicate_pad_numbers_are_jumpers no)
		(fp_line
			(start 1.603248 -1.500124)
			(end 1.603248 1.500124)
			(stroke
				(width 0.1524)
				(type default)
			)
			(layer "F.SilkS")
		)
		(fp_line
			(start -1.603248 -1.500124)
			(end 1.603248 -1.500124)
			(stroke
				(width 0.1524)
				(type default)
			)
			(layer "F.SilkS")
		)
		(fp_line
			(start 1.603248 1.500124)
			(end -1.603248 1.500124)
			(stroke
				(width 0.1524)
				(type default)
			)
			(layer "F.SilkS")
		)
		(fp_line
			(start -1.603248 1.500124)
			(end -1.603248 -1.500124)
			(stroke
				(width 0.1524)
				(type default)
			)
			(layer "F.SilkS")
		)
		(fp_line
			(start 0.700024 -1.500124)
			(end -0.700024 -1.500124)
			(stroke
				(width 0.1)
				(type default)
			)
			(layer "F.Fab")
		)
		(fp_line
			(start -0.700024 -1.500124)
			(end -0.700024 -1.169924)
			(stroke
				(width 0.1)
				(type default)
			)
			(layer "F.Fab")
		)
		(fp_line
			(start -0.700024 -1.169924)
			(end -1.249934 -1.169924)
			(stroke
				(width 0.1)
				(type default)
			)
			(layer "F.Fab")
		)
		(fp_line
			(start -1.249934 -1.169924)
			(end -1.249934 -0.729996)
			(stroke
				(width 0.1)
				(type default)
			)
			(layer "F.Fab")
		)
		(fp_line
			(start -0.6985 -0.729996)
			(end -0.6985 0.729996)
			(stroke
				(width 0.1)
				(type default)
			)
			(layer "F.Fab")
		)
		(fp_line
			(start -1.249934 -0.729996)
			(end -0.6985 -0.729996)
			(stroke
				(width 0.1)
				(type default)
			)
			(layer "F.Fab")
		)
		(fp_line
			(start 1.249934 -0.219964)
			(end 0.700024 -0.219964)
			(stroke
				(width 0.1)
				(type default)
			)
			(layer "F.Fab")
		)
		(fp_line
			(start 0.700024 -0.219964)
			(end 0.700024 -1.500124)
			(stroke
				(width 0.1)
				(type default)
			)
			(layer "F.Fab")
		)
		(fp_line
			(start 1.249934 0.219964)
			(end 1.249934 -0.219964)
			(stroke
				(width 0.1)
				(type default)
			)
			(layer "F.Fab")
		)
		(fp_line
			(start 0.700024 0.219964)
			(end 1.249934 0.219964)
			(stroke
				(width 0.1)
				(type default)
			)
			(layer "F.Fab")
		)
		(fp_line
			(start -0.6985 0.729996)
			(end -1.249934 0.729996)
			(stroke
				(width 0.1)
				(type default)
			)
			(layer "F.Fab")
		)
		(fp_line
			(start -1.249934 0.729996)
			(end -1.249934 1.169924)
			(stroke
				(width 0.1)
				(type default)
			)
			(layer "F.Fab")
		)
		(fp_line
			(start -0.700024 1.169924)
			(end -0.700024 1.500124)
			(stroke
				(width 0.1)
				(type default)
			)
			(layer "F.Fab")
		)
		(fp_line
			(start -1.249934 1.169924)
			(end -0.700024 1.169924)
			(stroke
				(width 0.1)
				(type default)
			)
			(layer "F.Fab")
		)
		(fp_line
			(start 0.700024 1.500124)
			(end 0.700024 0.219964)
			(stroke
				(width 0.1)
				(type default)
			)
			(layer "F.Fab")
		)
		(fp_line
			(start -0.700024 1.500124)
			(end 0.700024 1.500124)
			(stroke
				(width 0.1)
				(type default)
			)
			(layer "F.Fab")
		)
		(fp_rect
			(start -0.700024 1.500124)
			(end 0.700024 -1.500124)
			(stroke
				(width 0)
				(type default)
			)
			(fill no)
			(layer "F.Fab")
		)
		(pad "D" smd rect
			(at 0.999998 0)
			(size 0.8128 0.9144)
			(layers "F.Cu" "F.Mask" "F.Paste")
			(net "PVDDCR_CPU1_P1_EN1_ADDR_CFG")
		)
		(pad "G" smd rect
			(at -0.999998 -0.94996)
			(size 0.8128 0.9144)
			(layers "F.Cu" "F.Mask" "F.Paste")
			(net "PVDDIO_P1_EN_G")
		)
		(pad "S" smd rect
			(at -0.999998 0.94996)
			(size 0.8128 0.9144)
			(layers "F.Cu" "F.Mask" "F.Paste")
			(net "P3V3_AUX")
		)
	)
	(footprint ""
		(layer "F.Cu")
		(at 360.366056 -256.012188 90)
		(property "Reference" "C3927"
			(at 0 0 90)
			(layer "F.SilkS")
			(hide yes)
			(effects
				(font
					(size 1.27 1.27)
				)
			)
		)
		(property "Value" ""
			(at 0 0 90)
			(layer "F.Fab")
			(effects
				(font
					(size 1.27 1.27)
				)
			)
		)
		(duplicate_pad_numbers_are_jumpers no)
		(fp_line
			(start 0.7874 -0.4064)
			(end 0.7874 0.4064)
			(stroke
				(width 0.1524)
				(type default)
			)
			(layer "F.SilkS")
		)
		(fp_line
			(start -0.7874 -0.4064)
			(end 0.7874 -0.4064)
			(stroke
				(width 0.1524)
				(type default)
			)
			(layer "F.SilkS")
		)
		(fp_line
			(start 0.7874 0.4064)
			(end -0.7874 0.4064)
			(stroke
				(width 0.1524)
				(type default)
			)
			(layer "F.SilkS")
		)
		(fp_line
			(start -0.7874 0.4064)
			(end -0.7874 -0.4064)
			(stroke
				(width 0.1524)
				(type default)
			)
			(layer "F.SilkS")
		)
		(fp_line
			(start -0.12065 -0.305054)
			(end -0.12065 -0.2794)
			(stroke
				(width 0.1)
				(type default)
			)
			(layer "F.Fab")
		)
		(fp_line
			(start -0.67945 -0.305054)
			(end -0.12065 -0.305054)
			(stroke
				(width 0.1)
				(type default)
			)
			(layer "F.Fab")
		)
		(fp_line
			(start 0.67945 -0.3048)
			(end 0.67945 0.3048)
			(stroke
				(width 0.1)
				(type default)
			)
			(layer "F.Fab")
		)
		(fp_line
			(start 0.12065 -0.3048)
			(end 0.67945 -0.3048)
			(stroke
				(width 0.1)
				(type default)
			)
			(layer "F.Fab")
		)
		(fp_line
			(start 0.12065 -0.2794)
			(end 0.12065 -0.3048)
			(stroke
				(width 0.1)
				(type default)
			)
			(layer "F.Fab")
		)
		(fp_line
			(start -0.12065 -0.2794)
			(end 0.12065 -0.2794)
			(stroke
				(width 0.1)
				(type default)
			)
			(layer "F.Fab")
		)
		(fp_line
			(start 0.120396 0.2794)
			(end -0.12065 0.2794)
			(stroke
				(width 0.1)
				(type default)
			)
			(layer "F.Fab")
		)
		(fp_line
			(start -0.12065 0.2794)
			(end -0.12065 0.3048)
			(stroke
				(width 0.1)
				(type default)
			)
			(layer "F.Fab")
		)
		(fp_line
			(start 0.67945 0.3048)
			(end 0.120396 0.3048)
			(stroke
				(width 0.1)
				(type default)
			)
			(layer "F.Fab")
		)
		(fp_line
			(start 0.120396 0.3048)
			(end 0.120396 0.2794)
			(stroke
				(width 0.1)
				(type default)
			)
			(layer "F.Fab")
		)
		(fp_line
			(start -0.12065 0.3048)
			(end -0.67945 0.3048)
			(stroke
				(width 0.1)
				(type default)
			)
			(layer "F.Fab")
		)
		(fp_line
			(start -0.67945 0.3048)
			(end -0.67945 -0.305054)
			(stroke
				(width 0.1)
				(type default)
			)
			(layer "F.Fab")
		)
		(pad "1" smd circle
			(at -0.40005 0 90)
			(size 0 0)
			(layers "F.Cu" "F.Mask" "F.Paste")
			(net "PVDDCR_SOC_P0")
		)
		(pad "2" smd circle
			(at 0.40005 0 90)
			(size 0 0)
			(layers "F.Cu" "F.Mask" "F.Paste")
			(net "GND")
		)
	)
)
